# S9S_MB_2U (Grand Teton) — schematic netlist excerpt (pin names and nets, part order shuffled) for the footprints in the layout excerpt that follows; sources: Cadence DE-HDL packaged netlist, KiCad conversion of 03242023_DA0F0TMBIJ0_F0T_Motherboard_J_brd_V01_OCP.brd

J122  CONN1_10165288101LF  CONN1_10165288-101LF IO  pkg CON_GUIDE-F1XG  page 311 : NC1 = NC
R3572  Q_RES  33.2 1% CHIP  pkg 0402LF  page 172 : A = SMB_INA230_4_3V3AUX_SCL_R ; B = SMB_INA230_4_3V3AUX_SCL_R1

(kicad_pcb
	(version 20260206)
	(generator "pcbnew")
	(generator_version "10.0")
	(general
		(thickness 1.6)
		(legacy_teardrops no)
	)
	(paper "A4")
	(title_block
		(title "03242023_DA0F0TMBIJ0_F0T_Motherboard_J_brd_V01_OCP.brd")
		(comment 1 "Grand Teton / footprints 3974-3975 of 6105")
	)
	(layers
		(0 "F.Cu" signal "TOP")
		(4 "In1.Cu" signal "GND")
		(6 "In2.Cu" signal "IN1")
		(8 "In3.Cu" signal "GND1")
		(10 "In4.Cu" signal "IN2")
		(12 "In5.Cu" signal "GND2")
		(14 "In6.Cu" signal "IN3")
		(16 "In7.Cu" signal "GND3")
		(18 "In8.Cu" signal "VCC")
		(20 "In9.Cu" signal "VCC1")
		(22 "In10.Cu" signal "GND4")
		(24 "In11.Cu" signal "IN4")
		(26 "In12.Cu" signal "GND5")
		(28 "In13.Cu" signal "IN5")
		(30 "In14.Cu" signal "GND6")
		(32 "In15.Cu" signal "IN6")
		(34 "In16.Cu" signal "GND7")
		(2 "B.Cu" signal "BOTTOM")
		(9 "F.Adhes" user "F.Adhesive")
		(11 "B.Adhes" user "B.Adhesive")
		(13 "F.Paste" user "Package Geometry/Pastemask Top")
		(15 "B.Paste" user "Package Geometry/Pastemask Bottom")
		(5 "F.SilkS" user "Ref Des/Silkscreen Top")
		(7 "B.SilkS" user "Ref Des/Silkscreen Bottom")
		(1 "F.Mask" user "Board Geometry/Soldermask Top")
		(3 "B.Mask" user "Board Geometry/Soldermask Bottom")
		(17 "Dwgs.User" user "User.Drawings")
		(19 "Cmts.User" user "User.Comments")
		(21 "Eco1.User" user "User.Eco1")
		(23 "Eco2.User" user "User.Eco2")
		(25 "Edge.Cuts" user "Board Geometry/Outline")
		(27 "Margin" user)
		(31 "F.CrtYd" user "Package Geometry/Place Bound Top")
		(29 "B.CrtYd" user "Package Geometry/Place Bound Bottom")
		(35 "F.Fab" user "Ref Des/Assembly Top")
		(33 "B.Fab" user "Ref Des/Assembly Bottom")
	)
	(footprint ""
		(layer "F.Cu")
		(at 112.024922 -431.360072 180)
		(property "Reference" "J122"
			(at -4.893056 2.08026 0)
			(unlocked yes)
			(layer "F.SilkS")
			(effects
				(font
					(size 0.7874 0.5842)
					(thickness 0.1524)
				)
				(justify left)
			)
		)
		(property "Value" ""
			(at 0 0 180)
			(layer "F.Fab")
			(effects
				(font
					(size 1.27 1.27)
				)
			)
		)
		(duplicate_pad_numbers_are_jumpers no)
		(fp_line
			(start 3.525012 21.310092)
			(end 3.525012 7.151116)
			(stroke
				(width 0.1524)
				(type default)
			)
			(layer "F.SilkS")
		)
		(fp_line
			(start 3.525012 2.340356)
			(end 3.525012 -10.489946)
			(stroke
				(width 0.1524)
				(type default)
			)
			(layer "F.SilkS")
		)
		(fp_line
			(start 3.525012 -10.489946)
			(end -3.525012 -10.489946)
			(stroke
				(width 0.1524)
				(type default)
			)
			(layer "F.SilkS")
		)
		(fp_line
			(start -3.525012 21.310092)
			(end 3.525012 21.310092)
			(stroke
				(width 0.1524)
				(type default)
			)
			(layer "F.SilkS")
		)
		(fp_line
			(start -3.525012 10.6299)
			(end 3.525012 10.6299)
			(stroke
				(width 0.1524)
				(type default)
			)
			(layer "F.SilkS")
		)
		(fp_line
			(start -3.525012 -10.489946)
			(end -3.525012 21.310092)
			(stroke
				(width 0.1524)
				(type default)
			)
			(layer "F.SilkS")
		)
		(fp_line
			(start 3.525012 21.310092)
			(end 3.525012 -10.489946)
			(stroke
				(width 0.1)
				(type default)
			)
			(layer "F.Fab")
		)
		(fp_line
			(start 3.525012 -10.489946)
			(end -3.525012 -10.489946)
			(stroke
				(width 0.1)
				(type default)
			)
			(layer "F.Fab")
		)
		(fp_line
			(start -3.525012 21.310092)
			(end 3.525012 21.310092)
			(stroke
				(width 0.1)
				(type default)
			)
			(layer "F.Fab")
		)
		(fp_line
			(start -3.525012 -10.489946)
			(end -3.525012 21.310092)
			(stroke
				(width 0.1)
				(type default)
			)
			(layer "F.Fab")
		)
		(pad "" np_thru_hole circle
			(at 0 -6.620002 180)
			(size 3.175 3.175)
			(drill 3.175)
			(layers "*.Cu" "*.Mask")
			(clearance 0.381)
			(thermal_gap 0.381)
		)
		(pad "" np_thru_hole circle
			(at 0 0 180)
			(size 0 0)
			(drill 3.175)
			(layers "*.Cu" "*.Mask")
			(clearance 0)
		)
		(pad "" np_thru_hole circle
			(at 0 5.130038 180)
			(size 3.175 3.175)
			(drill 3.175)
			(layers "*.Cu" "*.Mask")
			(clearance 0.381)
			(thermal_gap 0.381)
		)
		(zone
			(layers "F.Cu" "B.Cu" "In1.Cu" "In2.Cu" "In3.Cu" "In4.Cu" "In5.Cu" "In6.Cu"
				"In7.Cu" "In8.Cu" "In9.Cu" "In10.Cu" "In11.Cu" "In12.Cu" "In13.Cu" "In14.Cu"
				"In15.Cu" "In16.Cu"
			)
			(hatch none 0.5)
			(connect_pads
				(clearance 0)
			)
			(min_thickness 0.25)
			(keepout
				(tracks not_allowed)
				(vias allowed)
				(pads allowed)
				(copperpour not_allowed)
				(footprints allowed)
			)
			(placement
				(enabled no)
				(sheetname "")
			)
			(fill
				(thermal_gap 0.5)
				(thermal_bridge_width 0.5)
				(island_removal_mode 0)
			)
			(polygon
				(pts
					(arc
						(start 114.120422 -436.49011)
						(mid 109.929422 -436.49011)
						(end 114.120422 -436.49011)
					)
				)
			)
		)
		(zone
			(layers "F.Cu" "B.Cu" "In1.Cu" "In2.Cu" "In3.Cu" "In4.Cu" "In5.Cu" "In6.Cu"
				"In7.Cu" "In8.Cu" "In9.Cu" "In10.Cu" "In11.Cu" "In12.Cu" "In13.Cu" "In14.Cu"
				"In15.Cu" "In16.Cu"
			)
			(hatch none 0.5)
			(connect_pads
				(clearance 0)
			)
			(min_thickness 0.25)
			(keepout
				(tracks not_allowed)
				(vias allowed)
				(pads allowed)
				(copperpour not_allowed)
				(footprints allowed)
			)
			(placement
				(enabled no)
				(sheetname "")
			)
			(fill
				(thermal_gap 0.5)
				(thermal_bridge_width 0.5)
				(island_removal_mode 0)
			)
			(polygon
				(pts
					(arc
						(start 114.120422 -424.74007)
						(mid 109.929422 -424.74007)
						(end 114.120422 -424.74007)
					)
				)
			)
		)
		(zone
			(layers "F.Cu" "B.Cu" "In1.Cu" "In2.Cu" "In3.Cu" "In4.Cu" "In5.Cu" "In6.Cu"
				"In7.Cu" "In8.Cu" "In9.Cu" "In10.Cu" "In11.Cu" "In12.Cu" "In13.Cu" "In14.Cu"
				"In15.Cu" "In16.Cu"
			)
			(hatch none 0.5)
			(connect_pads
				(clearance 0)
			)
			(min_thickness 0.25)
			(keepout
				(tracks not_allowed)
				(vias allowed)
				(pads allowed)
				(copperpour not_allowed)
				(footprints allowed)
			)
			(placement
				(enabled no)
				(sheetname "")
			)
			(fill
				(thermal_gap 0.5)
				(thermal_bridge_width 0.5)
				(island_removal_mode 0)
			)
			(polygon
				(pts
					(arc
						(start 115.644422 -431.360072)
						(mid 108.405422 -431.360072)
						(end 115.644422 -431.360072)
					)
				)
			)
		)
	)
	(footprint ""
		(layer "F.Cu")
		(at 152.32888 -47.970948 90)
		(property "Reference" "R3572"
			(at 0 0 90)
			(layer "F.SilkS")
			(hide yes)
			(effects
				(font
					(size 1.27 1.27)
				)
			)
		)
		(property "Value" ""
			(at 0 0 90)
			(layer "F.Fab")
			(effects
				(font
					(size 1.27 1.27)
				)
			)
		)
		(duplicate_pad_numbers_are_jumpers no)
		(fp_line
			(start 0.7874 -0.4064)
			(end 0.7874 0.4064)
			(stroke
				(width 0.1524)
				(type default)
			)
			(layer "F.SilkS")
		)
		(fp_line
			(start -0.7874 -0.4064)
			(end 0.7874 -0.4064)
			(stroke
				(width 0.1524)
				(type default)
			)
			(layer "F.SilkS")
		)
		(fp_line
			(start 0.7874 0.4064)
			(end -0.7874 0.4064)
			(stroke
				(width 0.1524)
				(type default)
			)
			(layer "F.SilkS")
		)
		(fp_line
			(start -0.7874 0.4064)
			(end -0.7874 -0.4064)
			(stroke
				(width 0.1524)
				(type default)
			)
			(layer "F.SilkS")
		)
		(fp_line
			(start -0.12065 -0.305054)
			(end -0.12065 -0.2794)
			(stroke
				(width 0.1)
				(type default)
			)
			(layer "F.Fab")
		)
		(fp_line
			(start -0.67945 -0.305054)
			(end -0.12065 -0.305054)
			(stroke
				(width 0.1)
				(type default)
			)
			(layer "F.Fab")
		)
		(fp_line
			(start 0.67945 -0.3048)
			(end 0.67945 0.3048)
			(stroke
				(width 0.1)
				(type default)
			)
			(layer "F.Fab")
		)
		(fp_line
			(start 0.12065 -0.3048)
			(end 0.67945 -0.3048)
			(stroke
				(width 0.1)
				(type default)
			)
			(layer "F.Fab")
		)
		(fp_line
			(start 0.12065 -0.2794)
			(end 0.12065 -0.3048)
			(stroke
				(width 0.1)
				(type default)
			)
			(layer "F.Fab")
		)
		(fp_line
			(start -0.12065 -0.2794)
			(end 0.12065 -0.2794)
			(stroke
				(width 0.1)
				(type default)
			)
			(layer "F.Fab")
		)
		(fp_line
			(start 0.120396 0.2794)
			(end -0.12065 0.2794)
			(stroke
				(width 0.1)
				(type default)
			)
			(layer "F.Fab")
		)
		(fp_line
			(start -0.12065 0.2794)
			(end -0.12065 0.3048)
			(stroke
				(width 0.1)
				(type default)
			)
			(layer "F.Fab")
		)
		(fp_line
			(start 0.67945 0.3048)
			(end 0.120396 0.3048)
			(stroke
				(width 0.1)
				(type default)
			)
			(layer "F.Fab")
		)
		(fp_line
			(start 0.120396 0.3048)
			(end 0.120396 0.2794)
			(stroke
				(width 0.1)
				(type default)
			)
			(layer "F.Fab")
		)
		(fp_line
			(start -0.12065 0.3048)
			(end -0.67945 0.3048)
			(stroke
				(width 0.1)
				(type default)
			)
			(layer "F.Fab")
		)
		(fp_line
			(start -0.67945 0.3048)
			(end -0.67945 -0.305054)
			(stroke
				(width 0.1)
				(type default)
			)
			(layer "F.Fab")
		)
		(pad "1" smd circle
			(at -0.40005 0 90)
			(size 0 0)
			(layers "F.Cu" "F.Mask" "F.Paste")
			(net "SMB_INA230_4_3V3AUX_SCL_R")
		)
		(pad "2" smd circle
			(at 0.40005 0 90)
			(size 0 0)
			(layers "F.Cu" "F.Mask" "F.Paste")
			(net "SMB_INA230_4_3V3AUX_SCL_R1")
		)
	)
)
